(kicad_pcb
	(version 20260206)
	(generator "pcbnew")
	(generator_version "10.0")
	(general
		(thickness 1.6)
		(legacy_teardrops no)
	)
	(paper "A4")
	(title_block
		(title "03242023_DA0F0TMBIJ0_F0T_Motherboard_J_brd_V01_OCP.brd")
		(comment 1 "Grand Teton / footprints 5713-5717 of 6105")
	)
	(layers
		(0 "F.Cu" signal "TOP")
		(4 "In1.Cu" signal "GND")
		(6 "In2.Cu" signal "IN1")
		(8 "In3.Cu" signal "GND1")
		(10 "In4.Cu" signal "IN2")
		(12 "In5.Cu" signal "GND2")
		(14 "In6.Cu" signal "IN3")
		(16 "In7.Cu" signal "GND3")
		(18 "In8.Cu" signal "VCC")
		(20 "In9.Cu" signal "VCC1")
		(22 "In10.Cu" signal "GND4")
		(24 "In11.Cu" signal "IN4")
		(26 "In12.Cu" signal "GND5")
		(28 "In13.Cu" signal "IN5")
		(30 "In14.Cu" signal "GND6")
		(32 "In15.Cu" signal "IN6")
		(34 "In16.Cu" signal "GND7")
		(2 "B.Cu" signal "BOTTOM")
		(9 "F.Adhes" user "F.Adhesive")
		(11 "B.Adhes" user "B.Adhesive")
		(13 "F.Paste" user "Package Geometry/Pastemask Top")
		(15 "B.Paste" user "Package Geometry/Pastemask Bottom")
		(5 "F.SilkS" user "Ref Des/Silkscreen Top")
		(7 "B.SilkS" user "Ref Des/Silkscreen Bottom")
		(1 "F.Mask" user "Board Geometry/Soldermask Top")
		(3 "B.Mask" user "Board Geometry/Soldermask Bottom")
		(17 "Dwgs.User" user "User.Drawings")
		(19 "Cmts.User" user "User.Comments")
		(21 "Eco1.User" user "User.Eco1")
		(23 "Eco2.User" user "User.Eco2")
		(25 "Edge.Cuts" user "Board Geometry/Outline")
		(27 "Margin" user)
		(31 "F.CrtYd" user "Package Geometry/Place Bound Top")
		(29 "B.CrtYd" user "Package Geometry/Place Bound Bottom")
		(35 "F.Fab" user "Ref Des/Assembly Top")
		(33 "B.Fab" user "Ref Des/Assembly Bottom")
	)
	(footprint ""
		(layer "B.Cu")
		(at 431.168556 -318.577976)
		(property "Reference" "R36"
			(at 0 0 0)
			(layer "B.SilkS")
			(hide yes)
			(effects
				(font
					(size 1.27 1.27)
				)
				(justify mirror)
			)
		)
		(property "Value" ""
			(at 0 0 0)
			(layer "B.Fab")
			(effects
				(font
					(size 1.27 1.27)
				)
				(justify mirror)
			)
		)
		(duplicate_pad_numbers_are_jumpers no)
		(fp_line
			(start -0.7874 -0.4064)
			(end -0.7874 0.4064)
			(stroke
				(width 0.1524)
				(type default)
			)
			(layer "B.SilkS")
		)
		(fp_line
			(start -0.7874 0.4064)
			(end 0.7874 0.4064)
			(stroke
				(width 0.1524)
				(type default)
			)
			(layer "B.SilkS")
		)
		(fp_line
			(start 0.7874 -0.4064)
			(end -0.7874 -0.4064)
			(stroke
				(width 0.1524)
				(type default)
			)
			(layer "B.SilkS")
		)
		(fp_line
			(start 0.7874 0.4064)
			(end 0.7874 -0.4064)
			(stroke
				(width 0.1524)
				(type default)
			)
			(layer "B.SilkS")
		)
		(fp_line
			(start -0.67945 -0.3048)
			(end -0.67945 0.3048)
			(stroke
				(width 0.1)
				(type default)
			)
			(layer "B.Fab")
		)
		(fp_line
			(start -0.67945 0.3048)
			(end -0.120396 0.3048)
			(stroke
				(width 0.1)
				(type default)
			)
			(layer "B.Fab")
		)
		(fp_line
			(start -0.12065 -0.3048)
			(end -0.67945 -0.3048)
			(stroke
				(width 0.1)
				(type default)
			)
			(layer "B.Fab")
		)
		(fp_line
			(start -0.12065 -0.2794)
			(end -0.12065 -0.3048)
			(stroke
				(width 0.1)
				(type default)
			)
			(layer "B.Fab")
		)
		(fp_line
			(start -0.120396 0.2794)
			(end 0.12065 0.2794)
			(stroke
				(width 0.1)
				(type default)
			)
			(layer "B.Fab")
		)
		(fp_line
			(start -0.120396 0.3048)
			(end -0.120396 0.2794)
			(stroke
				(width 0.1)
				(type default)
			)
			(layer "B.Fab")
		)
		(fp_line
			(start 0.12065 -0.305054)
			(end 0.12065 -0.2794)
			(stroke
				(width 0.1)
				(type default)
			)
			(layer "B.Fab")
		)
		(fp_line
			(start 0.12065 -0.2794)
			(end -0.12065 -0.2794)
			(stroke
				(width 0.1)
				(type default)
			)
			(layer "B.Fab")
		)
		(fp_line
			(start 0.12065 0.2794)
			(end 0.12065 0.3048)
			(stroke
				(width 0.1)
				(type default)
			)
			(layer "B.Fab")
		)
		(fp_line
			(start 0.12065 0.3048)
			(end 0.67945 0.3048)
			(stroke
				(width 0.1)
				(type default)
			)
			(layer "B.Fab")
		)
		(fp_line
			(start 0.67945 -0.305054)
			(end 0.12065 -0.305054)
			(stroke
				(width 0.1)
				(type default)
			)
			(layer "B.Fab")
		)
		(fp_line
			(start 0.67945 0.3048)
			(end 0.67945 -0.305054)
			(stroke
				(width 0.1)
				(type default)
			)
			(layer "B.Fab")
		)
		(pad "1" smd circle
			(at 0.40005 0 180)
			(size 0 0)
			(layers "B.Cu" "B.Mask" "B.Paste")
			(net "PD_CHF_CPU0_DIMM1_SAA")
		)
		(pad "2" smd circle
			(at -0.40005 0 180)
			(size 0 0)
			(layers "B.Cu" "B.Mask" "B.Paste")
			(net "GND")
		)
	)
	(footprint ""
		(layer "B.Cu")
		(at 256.286 -96.992948 -90)
		(property "Reference" "C173"
			(at 0 0 90)
			(layer "B.SilkS")
			(hide yes)
			(effects
				(font
					(size 1.27 1.27)
				)
				(justify mirror)
			)
		)
		(property "Value" ""
			(at 0 0 90)
			(layer "B.Fab")
			(effects
				(font
					(size 1.27 1.27)
				)
				(justify mirror)
			)
		)
		(duplicate_pad_numbers_are_jumpers no)
		(fp_line
			(start -0.7874 0.4064)
			(end 0.7874 0.4064)
			(stroke
				(width 0.1524)
				(type default)
			)
			(layer "B.SilkS")
		)
		(fp_line
			(start 0.7874 0.4064)
			(end 0.7874 -0.4064)
			(stroke
				(width 0.1524)
				(type default)
			)
			(layer "B.SilkS")
		)
		(fp_line
			(start -0.7874 -0.4064)
			(end -0.7874 0.4064)
			(stroke
				(width 0.1524)
				(type default)
			)
			(layer "B.SilkS")
		)
		(fp_line
			(start 0.7874 -0.4064)
			(end -0.7874 -0.4064)
			(stroke
				(width 0.1524)
				(type default)
			)
			(layer "B.SilkS")
		)
		(fp_line
			(start -0.67945 0.3048)
			(end -0.120396 0.3048)
			(stroke
				(width 0.1)
				(type default)
			)
			(layer "B.Fab")
		)
		(fp_line
			(start -0.120396 0.3048)
			(end -0.120396 0.2794)
			(stroke
				(width 0.1)
				(type default)
			)
			(layer "B.Fab")
		)
		(fp_line
			(start 0.12065 0.3048)
			(end 0.67945 0.3048)
			(stroke
				(width 0.1)
				(type default)
			)
			(layer "B.Fab")
		)
		(fp_line
			(start 0.67945 0.3048)
			(end 0.67945 -0.305054)
			(stroke
				(width 0.1)
				(type default)
			)
			(layer "B.Fab")
		)
		(fp_line
			(start -0.120396 0.2794)
			(end 0.12065 0.2794)
			(stroke
				(width 0.1)
				(type default)
			)
			(layer "B.Fab")
		)
		(fp_line
			(start 0.12065 0.2794)
			(end 0.12065 0.3048)
			(stroke
				(width 0.1)
				(type default)
			)
			(layer "B.Fab")
		)
		(fp_line
			(start -0.12065 -0.2794)
			(end -0.12065 -0.3048)
			(stroke
				(width 0.1)
				(type default)
			)
			(layer "B.Fab")
		)
		(fp_line
			(start 0.12065 -0.2794)
			(end -0.12065 -0.2794)
			(stroke
				(width 0.1)
				(type default)
			)
			(layer "B.Fab")
		)
		(fp_line
			(start -0.67945 -0.3048)
			(end -0.67945 0.3048)
			(stroke
				(width 0.1)
				(type default)
			)
			(layer "B.Fab")
		)
		(fp_line
			(start -0.12065 -0.3048)
			(end -0.67945 -0.3048)
			(stroke
				(width 0.1)
				(type default)
			)
			(layer "B.Fab")
		)
		(fp_line
			(start 0.12065 -0.305054)
			(end 0.12065 -0.2794)
			(stroke
				(width 0.1)
				(type default)
			)
			(layer "B.Fab")
		)
		(fp_line
			(start 0.67945 -0.305054)
			(end 0.12065 -0.305054)
			(stroke
				(width 0.1)
				(type default)
			)
			(layer "B.Fab")
		)
		(pad "1" smd circle
			(at 0.40005 0 90)
			(size 0 0)
			(layers "B.Cu" "B.Mask" "B.Paste")
			(net "P3V3_AUX_CLK_GEN_VDDA100M_CK440")
		)
		(pad "2" smd circle
			(at -0.40005 0 90)
			(size 0 0)
			(layers "B.Cu" "B.Mask" "B.Paste")
			(net "GND")
		)
	)
	(footprint ""
		(layer "B.Cu")
		(at 153.232104 -190.36411 90)
		(property "Reference" "R673"
			(at 0 0 90)
			(layer "B.SilkS")
			(hide yes)
			(effects
				(font
					(size 1.27 1.27)
				)
				(justify mirror)
			)
		)
		(property "Value" ""
			(at 0 0 90)
			(layer "B.Fab")
			(effects
				(font
					(size 1.27 1.27)
				)
				(justify mirror)
			)
		)
		(duplicate_pad_numbers_are_jumpers no)
		(fp_line
			(start 0.7874 -0.4064)
			(end -0.7874 -0.4064)
			(stroke
				(width 0.1524)
				(type default)
			)
			(layer "B.SilkS")
		)
		(fp_line
			(start -0.7874 -0.4064)
			(end -0.7874 0.4064)
			(stroke
				(width 0.1524)
				(type default)
			)
			(layer "B.SilkS")
		)
		(fp_line
			(start 0.7874 0.4064)
			(end 0.7874 -0.4064)
			(stroke
				(width 0.1524)
				(type default)
			)
			(layer "B.SilkS")
		)
		(fp_line
			(start -0.7874 0.4064)
			(end 0.7874 0.4064)
			(stroke
				(width 0.1524)
				(type default)
			)
			(layer "B.SilkS")
		)
		(fp_line
			(start 0.67945 -0.305054)
			(end 0.12065 -0.305054)
			(stroke
				(width 0.1)
				(type default)
			)
			(layer "B.Fab")
		)
		(fp_line
			(start 0.12065 -0.305054)
			(end 0.12065 -0.2794)
			(stroke
				(width 0.1)
				(type default)
			)
			(layer "B.Fab")
		)
		(fp_line
			(start -0.12065 -0.3048)
			(end -0.67945 -0.3048)
			(stroke
				(width 0.1)
				(type default)
			)
			(layer "B.Fab")
		)
		(fp_line
			(start -0.67945 -0.3048)
			(end -0.67945 0.3048)
			(stroke
				(width 0.1)
				(type default)
			)
			(layer "B.Fab")
		)
		(fp_line
			(start 0.12065 -0.2794)
			(end -0.12065 -0.2794)
			(stroke
				(width 0.1)
				(type default)
			)
			(layer "B.Fab")
		)
		(fp_line
			(start -0.12065 -0.2794)
			(end -0.12065 -0.3048)
			(stroke
				(width 0.1)
				(type default)
			)
			(layer "B.Fab")
		)
		(fp_line
			(start 0.12065 0.2794)
			(end 0.12065 0.3048)
			(stroke
				(width 0.1)
				(type default)
			)
			(layer "B.Fab")
		)
		(fp_line
			(start -0.120396 0.2794)
			(end 0.12065 0.2794)
			(stroke
				(width 0.1)
				(type default)
			)
			(layer "B.Fab")
		)
		(fp_line
			(start 0.67945 0.3048)
			(end 0.67945 -0.305054)
			(stroke
				(width 0.1)
				(type default)
			)
			(layer "B.Fab")
		)
		(fp_line
			(start 0.12065 0.3048)
			(end 0.67945 0.3048)
			(stroke
				(width 0.1)
				(type default)
			)
			(layer "B.Fab")
		)
		(fp_line
			(start -0.120396 0.3048)
			(end -0.120396 0.2794)
			(stroke
				(width 0.1)
				(type default)
			)
			(layer "B.Fab")
		)
		(fp_line
			(start -0.67945 0.3048)
			(end -0.120396 0.3048)
			(stroke
				(width 0.1)
				(type default)
			)
			(layer "B.Fab")
		)
		(pad "1" smd circle
			(at 0.40005 0 270)
			(size 0 0)
			(layers "B.Cu" "B.Mask" "B.Paste")
			(net "I3C_SPD_DDREFGH_CPU1_SDA")
		)
		(pad "2" smd circle
			(at -0.40005 0 270)
			(size 0 0)
			(layers "B.Cu" "B.Mask" "B.Paste")
			(net "I3C_SPD_DDREFGH_CPU1_R_SDA")
		)
	)
	(footprint ""
		(layer "B.Cu")
		(at 11.756136 -192.774824)
		(property "Reference" "U29"
			(at 1.6891 -2.880868 0)
			(unlocked yes)
			(layer "B.SilkS")
			(effects
				(font
					(size 0.7874 0.5842)
					(thickness 0.1524)
				)
				(justify left mirror)
			)
		)
		(property "Value" ""
			(at 0 0 0)
			(layer "B.Fab")
			(effects
				(font
					(size 1.27 1.27)
				)
				(justify mirror)
			)
		)
		(duplicate_pad_numbers_are_jumpers no)
		(fp_line
			(start -1.463548 -1.549908)
			(end -1.463548 1.549908)
			(stroke
				(width 0.1524)
				(type default)
			)
			(layer "B.SilkS")
		)
		(fp_line
			(start -1.463548 1.549908)
			(end 1.463548 1.549908)
			(stroke
				(width 0.1524)
				(type default)
			)
			(layer "B.SilkS")
		)
		(fp_line
			(start -0.762 -1.549908)
			(end -1.463548 -1.549908)
			(stroke
				(width 0.1524)
				(type default)
			)
			(layer "B.SilkS")
		)
		(fp_line
			(start 0 -0.762)
			(end -0.762 -1.549908)
			(stroke
				(width 0.1524)
				(type default)
			)
			(layer "B.SilkS")
		)
		(fp_line
			(start 0.787908 -1.549908)
			(end 0 -0.762)
			(stroke
				(width 0.1524)
				(type default)
			)
			(layer "B.SilkS")
		)
		(fp_line
			(start 1.463548 -1.549908)
			(end 0.787908 -1.549908)
			(stroke
				(width 0.1524)
				(type default)
			)
			(layer "B.SilkS")
		)
		(fp_line
			(start 1.463548 1.549908)
			(end 1.463548 -1.549908)
			(stroke
				(width 0.1524)
				(type default)
			)
			(layer "B.SilkS")
		)
		(fp_poly
			(pts
				(xy 3.4798 -1.359916) (xy 3.4798 -0.740156) (xy 2.86004 -1.050036)
			)
			(stroke
				(width 0)
				(type default)
			)
			(fill yes)
			(layer "B.SilkS")
		)
		(fp_line
			(start -1.549908 -1.549908)
			(end -1.549908 1.549908)
			(stroke
				(width 0.1)
				(type default)
			)
			(layer "B.Fab")
		)
		(fp_line
			(start -1.549908 1.549908)
			(end 1.549908 1.549908)
			(stroke
				(width 0.1)
				(type default)
			)
			(layer "B.Fab")
		)
		(fp_line
			(start 1.549908 -1.549908)
			(end -1.549908 -1.549908)
			(stroke
				(width 0.1)
				(type default)
			)
			(layer "B.Fab")
		)
		(fp_line
			(start 1.549908 1.549908)
			(end 1.549908 -1.549908)
			(stroke
				(width 0.1)
				(type default)
			)
			(layer "B.Fab")
		)
		(fp_poly
			(pts
				(xy 3.4798 -1.359916) (xy 2.86004 -1.050036) (xy 3.4798 -0.740156)
			)
			(stroke
				(width 0)
				(type default)
			)
			(fill yes)
			(layer "B.Fab")
		)
		(pad "1" smd rect
			(at 2.175002 -1.050036 90)
			(size 0.6096 1.1684)
			(layers "B.Cu" "B.Mask" "B.Paste")
			(net "PVNN_TERM_CPU1")
		)
		(pad "2" smd rect
			(at 2.175002 -0.32512 90)
			(size 0.4318 1.1684)
			(layers "B.Cu" "B.Mask" "B.Paste")
			(net "SMB_PEHPCPU1_GTL_R_SCL")
		)
		(pad "3" smd rect
			(at 2.175002 0.32512 90)
			(size 0.4318 1.1684)
			(layers "B.Cu" "B.Mask" "B.Paste")
			(net "SMB_PEHPCPU1_GTL_R_SDA")
		)
		(pad "4" smd rect
			(at 2.175002 1.050036 90)
			(size 0.6096 1.1684)
			(layers "B.Cu" "B.Mask" "B.Paste")
			(net "GND")
		)
		(pad "5" smd rect
			(at -2.175002 1.050036 90)
			(size 0.6096 1.1684)
			(layers "B.Cu" "B.Mask" "B.Paste")
			(net "TP_SMB_PEHPCPU1_EN")
		)
		(pad "6" smd rect
			(at -2.175002 0.32512 90)
			(size 0.4318 1.1684)
			(layers "B.Cu" "B.Mask" "B.Paste")
			(net "SMB_PEHPCPU1_LVC3_SDA_R0")
		)
		(pad "7" smd rect
			(at -2.175002 -0.32512 90)
			(size 0.4318 1.1684)
			(layers "B.Cu" "B.Mask" "B.Paste")
			(net "SMB_PEHPCPU1_LVC3_SCL_R0")
		)
		(pad "8" smd rect
			(at -2.175002 -1.050036 90)
			(size 0.6096 1.1684)
			(layers "B.Cu" "B.Mask" "B.Paste")
			(net "P3V3_AUX")
		)
	)
	(footprint ""
		(layer "B.Cu")
		(at 227.071174 -128.74625 180)
		(property "Reference" "R4516"
			(at 0 0 0)
			(layer "B.SilkS")
			(hide yes)
			(effects
				(font
					(size 1.27 1.27)
				)
				(justify mirror)
			)
		)
		(property "Value" ""
			(at 0 0 0)
			(layer "B.Fab")
			(effects
				(font
					(size 1.27 1.27)
				)
				(justify mirror)
			)
		)
		(duplicate_pad_numbers_are_jumpers no)
		(fp_line
			(start 0.7874 0.4064)
			(end 0.7874 -0.4064)
			(stroke
				(width 0.1524)
				(type default)
			)
			(layer "B.SilkS")
		)
		(fp_line
			(start 0.7874 -0.4064)
			(end -0.7874 -0.4064)
			(stroke
				(width 0.1524)
				(type default)
			)
			(layer "B.SilkS")
		)
		(fp_line
			(start -0.7874 0.4064)
			(end 0.7874 0.4064)
			(stroke
				(width 0.1524)
				(type default)
			)
			(layer "B.SilkS")
		)
		(fp_line
			(start -0.7874 -0.4064)
			(end -0.7874 0.4064)
			(stroke
				(width 0.1524)
				(type default)
			)
			(layer "B.SilkS")
		)
		(fp_line
			(start 0.67945 0.3048)
			(end 0.67945 -0.305054)
			(stroke
				(width 0.1)
				(type default)
			)
			(layer "B.Fab")
		)
		(fp_line
			(start 0.67945 -0.305054)
			(end 0.12065 -0.305054)
			(stroke
				(width 0.1)
				(type default)
			)
			(layer "B.Fab")
		)
		(fp_line
			(start 0.12065 0.3048)
			(end 0.67945 0.3048)
			(stroke
				(width 0.1)
				(type default)
			)
			(layer "B.Fab")
		)
		(fp_line
			(start 0.12065 0.2794)
			(end 0.12065 0.3048)
			(stroke
				(width 0.1)
				(type default)
			)
			(layer "B.Fab")
		)
		(fp_line
			(start 0.12065 -0.2794)
			(end -0.12065 -0.2794)
			(stroke
				(width 0.1)
				(type default)
			)
			(layer "B.Fab")
		)
		(fp_line
			(start 0.12065 -0.305054)
			(end 0.12065 -0.2794)
			(stroke
				(width 0.1)
				(type default)
			)
			(layer "B.Fab")
		)
		(fp_line
			(start -0.120396 0.3048)
			(end -0.120396 0.2794)
			(stroke
				(width 0.1)
				(type default)
			)
			(layer "B.Fab")
		)
		(fp_line
			(start -0.120396 0.2794)
			(end 0.12065 0.2794)
			(stroke
				(width 0.1)
				(type default)
			)
			(layer "B.Fab")
		)
		(fp_line
			(start -0.12065 -0.2794)
			(end -0.12065 -0.3048)
			(stroke
				(width 0.1)
				(type default)
			)
			(layer "B.Fab")
		)
		(fp_line
			(start -0.12065 -0.3048)
			(end -0.67945 -0.3048)
			(stroke
				(width 0.1)
				(type default)
			)
			(layer "B.Fab")
		)
		(fp_line
			(start -0.67945 0.3048)
			(end -0.120396 0.3048)
			(stroke
				(width 0.1)
				(type default)
			)
			(layer "B.Fab")
		)
		(fp_line
			(start -0.67945 -0.3048)
			(end -0.67945 0.3048)
			(stroke
				(width 0.1)
				(type default)
			)
			(layer "B.Fab")
		)
		(pad "1" smd circle
			(at 0.40005 0)
			(size 0 0)
			(layers "B.Cu" "B.Mask" "B.Paste")
			(net "P3V3")
		)
		(pad "2" smd circle
			(at -0.40005 0)
			(size 0 0)
			(layers "B.Cu" "B.Mask" "B.Paste")
			(net "CLK_SWB_OE_N")
		)
	)
)
